(kicad_pcb
	(version 20241229)
	(generator "pcbnew")
	(generator_version "9.0")
	(general
		(thickness 1.599998)
		(legacy_teardrops no)
	)
	(paper "A4")
	(title_block
		(date "2023-02-12")
		(rev "1.1.5")
		(comment 9 "footprint 108 of 473 (U3), pads 79-154 of 484")
	)
	(layers
		(0 "F.Cu" signal)
		(4 "In1.Cu" power "In1.GND")
		(6 "In2.Cu" signal)
		(8 "In3.Cu" power "In3.GND")
		(10 "In4.Cu" power "In4.VCC")
		(12 "In5.Cu" signal)
		(14 "In6.Cu" power "In6.VCC")
		(2 "B.Cu" signal)
		(9 "F.Adhes" user "F.Adhesive")
		(11 "B.Adhes" user "B.Adhesive")
		(13 "F.Paste" user)
		(15 "B.Paste" user)
		(5 "F.SilkS" user "F.Silkscreen")
		(7 "B.SilkS" user "B.Silkscreen")
		(1 "F.Mask" user)
		(3 "B.Mask" user)
		(17 "Dwgs.User" user "User.Drawings")
		(19 "Cmts.User" user "User.Comments")
		(21 "Eco1.User" user "User.Eco1")
		(23 "Eco2.User" user "User.Eco2")
		(25 "Edge.Cuts" user)
		(27 "Margin" user)
		(31 "F.CrtYd" user "F.Courtyard")
		(29 "B.CrtYd" user "B.Courtyard")
		(35 "F.Fab" user)
		(33 "B.Fab" user)
	)
	(footprint "antmicro-footprints:BGA-484_23x23mm_Layout22x22_P1mm_FBG484"
		(locked yes)
		(layer "F.Cu")
		(at 169.036328 95.997157 -90)
		(property "Reference" "U3"
			(at -11.8 -12 270)
			(layer "F.SilkS")
			(effects
				(font
					(size 0.7 0.7)
					(thickness 0.15)
				)
				(justify left bottom)
			)
		)
		(property "Value" "XC7K70T-FBG484"
			(at -10.4 0.4 270)
			(layer "F.Fab")
			(effects
				(font
					(size 0.7 0.7)
					(thickness 0.15)
				)
				(justify left bottom)
			)
		)
		(property "Description" "Kintex®-7 Field Programmable Gate Array (FPGA) IC 285 484-BBGA, FCBGA"
			(at 0 0 270)
			(layer "F.Fab")
			(hide yes)
			(effects
				(font
					(size 1.27 1.27)
					(thickness 0.15)
				)
			)
		)
		(property "Author" "Antmicro"
			(at 73.039171 265.033485 0)
			(layer "F.Fab")
			(hide yes)
			(effects
				(font
					(size 1 1)
					(thickness 0.15)
				)
			)
		)
		(property "License" "Apache-2.0"
			(at 73.039171 265.033485 0)
			(layer "F.Fab")
			(hide yes)
			(effects
				(font
					(size 1 1)
					(thickness 0.15)
				)
			)
		)
		(property "MPN" "XC7K70T-1FBG484C"
			(at 73.039171 265.033485 0)
			(layer "F.Fab")
			(hide yes)
			(effects
				(font
					(size 1 1)
					(thickness 0.15)
				)
			)
		)
		(property "Manufacturer" "AMD-Xilinx"
			(at 73.039171 265.033485 0)
			(layer "F.Fab")
			(hide yes)
			(effects
				(font
					(size 1 1)
					(thickness 0.15)
				)
			)
		)
		(sheetname "FPGA Banks")
		(sheetfile "fpga-banks.kicad_sch")
		(attr smd)
		(pad "B13" smd circle
			(at 1.5 -9.5 270)
			(size 0.51 0.51)
			(layers "F.Cu" "F.Mask" "F.Paste")
			(net 301 "unconnected-(U3G-IO_L5N_T0_AD2N_15-PadB13)")
			(pinfunction "IO_L5N_T0_AD2N_15")
			(pintype "bidirectional+no_connect")
		)
		(pad "B14" smd circle
			(at 2.5 -9.5 270)
			(size 0.51 0.51)
			(layers "F.Cu" "F.Mask" "F.Paste")
			(net 459 "3V3_SYS")
			(pinfunction "VCCO_15")
			(pintype "passive")
		)
		(pad "B15" smd circle
			(at 3.5 -9.5 270)
			(size 0.51 0.51)
			(layers "F.Cu" "F.Mask" "F.Paste")
			(net 37 "ETH_RXD2")
			(pinfunction "IO_L9P_T1_DQS_AD11P_15")
			(pintype "bidirectional")
		)
		(pad "B16" smd circle
			(at 4.5 -9.5 270)
			(size 0.51 0.51)
			(layers "F.Cu" "F.Mask" "F.Paste")
			(net 22 "ETH_RXD0")
			(pinfunction "IO_L8P_T1_AD3P_15")
			(pintype "bidirectional")
		)
		(pad "B17" smd circle
			(at 5.5 -9.5 270)
			(size 0.51 0.51)
			(layers "F.Cu" "F.Mask" "F.Paste")
			(net 35 "ETH_MDC")
			(pinfunction "IO_L10P_T1_AD4P_15")
			(pintype "bidirectional")
		)
		(pad "B18" smd circle
			(at 6.5 -9.5 270)
			(size 0.51 0.51)
			(layers "F.Cu" "F.Mask" "F.Paste")
			(net 302 "unconnected-(U3G-IO_L20P_T3_A20_15-PadB18)")
			(pinfunction "IO_L20P_T3_A20_15")
			(pintype "bidirectional+no_connect")
		)
		(pad "B19" smd circle
			(at 7.5 -9.5 270)
			(size 0.51 0.51)
			(layers "F.Cu" "F.Mask" "F.Paste")
			(net 5 "GND")
			(pinfunction "GND")
			(pintype "passive")
		)
		(pad "B20" smd circle
			(at 8.5 -9.5 270)
			(size 0.51 0.51)
			(layers "F.Cu" "F.Mask" "F.Paste")
			(net 27 "ETH_TXD1")
			(pinfunction "IO_L24P_T3_RS1_15")
			(pintype "bidirectional")
		)
		(pad "B21" smd circle
			(at 9.5 -9.5 270)
			(size 0.51 0.51)
			(layers "F.Cu" "F.Mask" "F.Paste")
			(net 32 "ETH_TXD0")
			(pinfunction "IO_L24N_T3_RS0_15")
			(pintype "bidirectional")
		)
		(pad "B22" smd circle
			(at 10.5 -9.5 270)
			(size 0.51 0.51)
			(layers "F.Cu" "F.Mask" "F.Paste")
			(net 198 "SD_CD")
			(pinfunction "IO_L21N_T3_DQS_A18_15")
			(pintype "bidirectional")
		)
		(pad "C1" smd circle
			(at -10.5 -8.5 270)
			(size 0.51 0.51)
			(layers "F.Cu" "F.Mask" "F.Paste")
			(net 5 "GND")
			(pinfunction "GND")
			(pintype "passive")
		)
		(pad "C2" smd circle
			(at -9.5 -8.5 270)
			(size 0.51 0.51)
			(layers "F.Cu" "F.Mask" "F.Paste")
			(net 271 "unconnected-(U3A-MGTAVTT-PadA2)")
			(pinfunction "MGTAVTT")
			(pintype "passive+no_connect")
		)
		(pad "C3" smd circle
			(at -8.5 -8.5 270)
			(size 0.51 0.51)
			(layers "F.Cu" "F.Mask" "F.Paste")
			(net 303 "unconnected-(U3C-MGTXRXN2_115-PadC3)")
			(pinfunction "MGTXRXN2_115")
			(pintype "bidirectional+no_connect")
		)
		(pad "C4" smd circle
			(at -7.5 -8.5 270)
			(size 0.51 0.51)
			(layers "F.Cu" "F.Mask" "F.Paste")
			(net 304 "unconnected-(U3C-MGTXRXP2_115-PadC4)")
			(pinfunction "MGTXRXP2_115")
			(pintype "bidirectional+no_connect")
		)
		(pad "C5" smd circle
			(at -6.5 -8.5 270)
			(size 0.51 0.51)
			(layers "F.Cu" "F.Mask" "F.Paste")
			(net 5 "GND")
			(pinfunction "GND")
			(pintype "passive")
		)
		(pad "C6" smd circle
			(at -5.5 -8.5 270)
			(size 0.51 0.51)
			(layers "F.Cu" "F.Mask" "F.Paste")
			(net 275 "unconnected-(U3A-MGTAVCC-PadA6)")
			(pinfunction "MGTAVCC")
			(pintype "passive+no_connect")
		)
		(pad "C7" smd circle
			(at -4.5 -8.5 270)
			(size 0.51 0.51)
			(layers "F.Cu" "F.Mask" "F.Paste")
			(net 5 "GND")
			(pinfunction "GND")
			(pintype "passive")
		)
		(pad "C8" smd circle
			(at -3.5 -8.5 270)
			(size 0.51 0.51)
			(layers "F.Cu" "F.Mask" "F.Paste")
			(net 59 "USR_LED2")
			(pinfunction "IO_L22P_T3_16")
			(pintype "bidirectional")
		)
		(pad "C9" smd circle
			(at -2.5 -8.5 270)
			(size 0.51 0.51)
			(layers "F.Cu" "F.Mask" "F.Paste")
			(net 392 "USR_BTN3")
			(pinfunction "IO_L19N_T3_VREF_16")
			(pintype "bidirectional")
		)
		(pad "C10" smd circle
			(at -1.5 -8.5 270)
			(size 0.51 0.51)
			(layers "F.Cu" "F.Mask" "F.Paste")
			(net 305 "unconnected-(U3F-IO_L7N_T1_16-PadC10)")
			(pinfunction "IO_L7N_T1_16")
			(pintype "bidirectional+no_connect")
		)
		(pad "C11" smd circle
			(at -0.5 -8.5 270)
			(size 0.51 0.51)
			(layers "F.Cu" "F.Mask" "F.Paste")
			(net 459 "3V3_SYS")
			(pinfunction "VCCO_16")
			(pintype "power_in")
		)
		(pad "C12" smd circle
			(at 0.5 -8.5 270)
			(size 0.51 0.51)
			(layers "F.Cu" "F.Mask" "F.Paste")
			(net 26 "ETH_REF_CLK")
			(pinfunction "IO_L2P_T0_AD8P_15")
			(pintype "bidirectional")
		)
		(pad "C13" smd circle
			(at 1.5 -8.5 270)
			(size 0.51 0.51)
			(layers "F.Cu" "F.Mask" "F.Paste")
			(net 306 "unconnected-(U3G-IO_L5P_T0_AD2P_15-PadC13)")
			(pinfunction "IO_L5P_T0_AD2P_15")
			(pintype "bidirectional+no_connect")
		)
		(pad "C14" smd circle
			(at 2.5 -8.5 270)
			(size 0.51 0.51)
			(layers "F.Cu" "F.Mask" "F.Paste")
			(net 25 "ETH_MDIO")
			(pinfunction "IO_L7P_T1_AD10P_15")
			(pintype "bidirectional")
		)
		(pad "C15" smd circle
			(at 3.5 -8.5 270)
			(size 0.51 0.51)
			(layers "F.Cu" "F.Mask" "F.Paste")
			(net 541 "ETH_INT_N")
			(pinfunction "IO_L7N_T1_AD10N_15")
			(pintype "bidirectional")
		)
		(pad "C16" smd circle
			(at 4.5 -8.5 270)
			(size 0.51 0.51)
			(layers "F.Cu" "F.Mask" "F.Paste")
			(net 5 "GND")
			(pinfunction "GND")
			(pintype "passive")
		)
		(pad "C17" smd circle
			(at 5.5 -8.5 270)
			(size 0.51 0.51)
			(layers "F.Cu" "F.Mask" "F.Paste")
			(net 36 "ETH_RX_CLK")
			(pinfunction "IO_L12P_T1_MRCC_AD5P_15")
			(pintype "bidirectional")
		)
		(pad "C18" smd circle
			(at 6.5 -8.5 270)
			(size 0.51 0.51)
			(layers "F.Cu" "F.Mask" "F.Paste")
			(net 307 "unconnected-(U3G-IO_L12N_T1_MRCC_AD5N_15-PadC18)")
			(pinfunction "IO_L12N_T1_MRCC_AD5N_15")
			(pintype "bidirectional+no_connect")
		)
		(pad "C19" smd circle
			(at 7.5 -8.5 270)
			(size 0.51 0.51)
			(layers "F.Cu" "F.Mask" "F.Paste")
			(net 308 "unconnected-(U3G-IO_L19P_T3_A22_15-PadC19)")
			(pinfunction "IO_L19P_T3_A22_15")
			(pintype "bidirectional+no_connect")
		)
		(pad "C20" smd circle
			(at 8.5 -8.5 270)
			(size 0.51 0.51)
			(layers "F.Cu" "F.Mask" "F.Paste")
			(net 195 "SD_CMD")
			(pinfunction "IO_L19N_T3_A21_VREF_15")
			(pintype "bidirectional")
		)
		(pad "C21" smd circle
			(at 9.5 -8.5 270)
			(size 0.51 0.51)
			(layers "F.Cu" "F.Mask" "F.Paste")
			(net 459 "3V3_SYS")
			(pinfunction "VCCO_15")
			(pintype "passive")
		)
		(pad "C22" smd circle
			(at 10.5 -8.5 270)
			(size 0.51 0.51)
			(layers "F.Cu" "F.Mask" "F.Paste")
			(net 192 "SD_DAT1")
			(pinfunction "IO_L21P_T3_DQS_15")
			(pintype "bidirectional")
		)
		(pad "D1" smd circle
			(at -10.5 -7.5 270)
			(size 0.51 0.51)
			(layers "F.Cu" "F.Mask" "F.Paste")
			(net 309 "unconnected-(U3C-MGTXTXN1_115-PadD1)")
			(pinfunction "MGTXTXN1_115")
			(pintype "bidirectional+no_connect")
		)
		(pad "D2" smd circle
			(at -9.5 -7.5 270)
			(size 0.51 0.51)
			(layers "F.Cu" "F.Mask" "F.Paste")
			(net 310 "unconnected-(U3C-MGTXTXP1_115-PadD2)")
			(pinfunction "MGTXTXP1_115")
			(pintype "bidirectional+no_connect")
		)
		(pad "D3" smd circle
			(at -8.5 -7.5 270)
			(size 0.51 0.51)
			(layers "F.Cu" "F.Mask" "F.Paste")
			(net 5 "GND")
			(pinfunction "GND")
			(pintype "passive")
		)
		(pad "D4" smd circle
			(at -7.5 -7.5 270)
			(size 0.51 0.51)
			(layers "F.Cu" "F.Mask" "F.Paste")
			(net 5 "GND")
			(pinfunction "GND")
			(pintype "passive")
		)
		(pad "D5" smd circle
			(at -6.5 -7.5 270)
			(size 0.51 0.51)
			(layers "F.Cu" "F.Mask" "F.Paste")
			(net 311 "unconnected-(U3C-MGTREFCLK0N_115-PadD5)")
			(pinfunction "MGTREFCLK0N_115")
			(pintype "bidirectional+no_connect")
		)
		(pad "D6" smd circle
			(at -5.5 -7.5 270)
			(size 0.51 0.51)
			(layers "F.Cu" "F.Mask" "F.Paste")
			(net 312 "unconnected-(U3C-MGTREFCLK0P_115-PadD6)")
			(pinfunction "MGTREFCLK0P_115")
			(pintype "bidirectional+no_connect")
		)
		(pad "D7" smd circle
			(at -4.5 -7.5 270)
			(size 0.51 0.51)
			(layers "F.Cu" "F.Mask" "F.Paste")
			(net 5 "GND")
			(pinfunction "GND")
			(pintype "passive")
		)
		(pad "D8" smd circle
			(at -3.5 -7.5 270)
			(size 0.51 0.51)
			(layers "F.Cu" "F.Mask" "F.Paste")
			(net 459 "3V3_SYS")
			(pinfunction "VCCO_16")
			(pintype "passive")
		)
		(pad "D9" smd circle
			(at -2.5 -7.5 270)
			(size 0.51 0.51)
			(layers "F.Cu" "F.Mask" "F.Paste")
			(net 61 "USR_LED4")
			(pinfunction "IO_L19P_T3_16")
			(pintype "bidirectional")
		)
		(pad "D10" smd circle
			(at -1.5 -7.5 270)
			(size 0.51 0.51)
			(layers "F.Cu" "F.Mask" "F.Paste")
			(net 313 "unconnected-(U3F-IO_L7P_T1_16-PadD10)")
			(pinfunction "IO_L7P_T1_16")
			(pintype "bidirectional+no_connect")
		)
		(pad "D11" smd circle
			(at -0.5 -7.5 270)
			(size 0.51 0.51)
			(layers "F.Cu" "F.Mask" "F.Paste")
			(net 314 "unconnected-(U3F-IO_L12N_T1_MRCC_16-PadD11)")
			(pinfunction "IO_L12N_T1_MRCC_16")
			(pintype "bidirectional+no_connect")
		)
		(pad "D12" smd circle
			(at 0.5 -7.5 270)
			(size 0.51 0.51)
			(layers "F.Cu" "F.Mask" "F.Paste")
			(net 315 "unconnected-(U3G-IO_0_15-PadD12)")
			(pinfunction "IO_0_15")
			(pintype "bidirectional+no_connect")
		)
		(pad "D13" smd circle
			(at 1.5 -7.5 270)
			(size 0.51 0.51)
			(layers "F.Cu" "F.Mask" "F.Paste")
			(net 5 "GND")
			(pinfunction "GND")
			(pintype "passive")
		)
		(pad "D14" smd circle
			(at 2.5 -7.5 270)
			(size 0.51 0.51)
			(layers "F.Cu" "F.Mask" "F.Paste")
			(net 316 "unconnected-(U3G-IO_L6N_T0_VREF_15-PadD14)")
			(pinfunction "IO_L6N_T0_VREF_15")
			(pintype "bidirectional+no_connect")
		)
		(pad "D15" smd circle
			(at 3.5 -7.5 270)
			(size 0.51 0.51)
			(layers "F.Cu" "F.Mask" "F.Paste")
			(net 317 "unconnected-(U3G-IO_L11P_T1_SRCC_AD12P_15-PadD15)")
			(pinfunction "IO_L11P_T1_SRCC_AD12P_15")
			(pintype "bidirectional+no_connect")
		)
		(pad "D16" smd circle
			(at 4.5 -7.5 270)
			(size 0.51 0.51)
			(layers "F.Cu" "F.Mask" "F.Paste")
			(net 318 "unconnected-(U3G-IO_L11N_T1_SRCC_AD12N_15-PadD16)")
			(pinfunction "IO_L11N_T1_SRCC_AD12N_15")
			(pintype "bidirectional+no_connect")
		)
		(pad "D17" smd circle
			(at 5.5 -7.5 270)
			(size 0.51 0.51)
			(layers "F.Cu" "F.Mask" "F.Paste")
			(net 319 "unconnected-(U3G-IO_L14N_T2_SRCC_15-PadD17)")
			(pinfunction "IO_L14N_T2_SRCC_15")
			(pintype "bidirectional+no_connect")
		)
		(pad "D18" smd circle
			(at 6.5 -7.5 270)
			(size 0.51 0.51)
			(layers "F.Cu" "F.Mask" "F.Paste")
			(net 459 "3V3_SYS")
			(pinfunction "VCCO_15")
			(pintype "passive")
		)
		(pad "D19" smd circle
			(at 7.5 -7.5 270)
			(size 0.51 0.51)
			(layers "F.Cu" "F.Mask" "F.Paste")
			(net 197 "SD_DAT2")
			(pinfunction "IO_L18P_T2_A24_15")
			(pintype "bidirectional")
		)
		(pad "D20" smd circle
			(at 8.5 -7.5 270)
			(size 0.51 0.51)
			(layers "F.Cu" "F.Mask" "F.Paste")
			(net 196 "SD_DAT3")
			(pinfunction "IO_L18N_T2_A23_15")
			(pintype "bidirectional")
		)
		(pad "D21" smd circle
			(at 9.5 -7.5 270)
			(size 0.51 0.51)
			(layers "F.Cu" "F.Mask" "F.Paste")
			(net 193 "SD_DAT0")
			(pinfunction "IO_L23P_T3_FOE_B_15")
			(pintype "bidirectional")
		)
		(pad "D22" smd circle
			(at 10.5 -7.5 270)
			(size 0.51 0.51)
			(layers "F.Cu" "F.Mask" "F.Paste")
			(net 194 "SD_CLK")
			(pinfunction "IO_L23N_T3_FWE_B_15")
			(pintype "bidirectional")
		)
		(pad "E1" smd circle
			(at -10.5 -6.5 270)
			(size 0.51 0.51)
			(layers "F.Cu" "F.Mask" "F.Paste")
			(net 5 "GND")
			(pinfunction "GND")
			(pintype "passive")
		)
		(pad "E2" smd circle
			(at -9.5 -6.5 270)
			(size 0.51 0.51)
			(layers "F.Cu" "F.Mask" "F.Paste")
			(net 271 "unconnected-(U3A-MGTAVTT-PadA2)")
			(pinfunction "MGTAVTT")
			(pintype "passive+no_connect")
		)
		(pad "E3" smd circle
			(at -8.5 -6.5 270)
			(size 0.51 0.51)
			(layers "F.Cu" "F.Mask" "F.Paste")
			(net 320 "unconnected-(U3C-MGTXRXN1_115-PadE3)")
			(pinfunction "MGTXRXN1_115")
			(pintype "bidirectional+no_connect")
		)
		(pad "E4" smd circle
			(at -7.5 -6.5 270)
			(size 0.51 0.51)
			(layers "F.Cu" "F.Mask" "F.Paste")
			(net 321 "unconnected-(U3C-MGTXRXP1_115-PadE4)")
			(pinfunction "MGTXRXP1_115")
			(pintype "bidirectional+no_connect")
		)
		(pad "E5" smd circle
			(at -6.5 -6.5 270)
			(size 0.51 0.51)
			(layers "F.Cu" "F.Mask" "F.Paste")
			(net 5 "GND")
			(pinfunction "GND")
			(pintype "passive")
		)
		(pad "E6" smd circle
			(at -5.5 -6.5 270)
			(size 0.51 0.51)
			(layers "F.Cu" "F.Mask" "F.Paste")
			(net 275 "unconnected-(U3A-MGTAVCC-PadA6)")
			(pinfunction "MGTAVCC")
			(pintype "passive+no_connect")
		)
		(pad "E7" smd circle
			(at -4.5 -6.5 270)
			(size 0.51 0.51)
			(layers "F.Cu" "F.Mask" "F.Paste")
			(net 5 "GND")
			(pinfunction "GND")
			(pintype "passive")
		)
		(pad "E8" smd circle
			(at -3.5 -6.5 270)
			(size 0.51 0.51)
			(layers "F.Cu" "F.Mask" "F.Paste")
			(net 390 "USR_BTN1")
			(pinfunction "IO_24_T3_16")
			(pintype "bidirectional")
		)
		(pad "E9" smd circle
			(at -2.5 -6.5 270)
			(size 0.51 0.51)
			(layers "F.Cu" "F.Mask" "F.Paste")
			(net 436 "USR_BTN4")
			(pinfunction "IO_L15N_T2_DQS_16")
			(pintype "bidirectional")
		)
		(pad "E10" smd circle
			(at -1.5 -6.5 270)
			(size 0.51 0.51)
			(layers "F.Cu" "F.Mask" "F.Paste")
			(net 5 "GND")
			(pinfunction "GND")
			(pintype "passive")
		)
		(pad "E11" smd circle
			(at -0.5 -6.5 270)
			(size 0.51 0.51)
			(layers "F.Cu" "F.Mask" "F.Paste")
			(net 322 "unconnected-(U3F-IO_L12P_T1_MRCC_16-PadE11)")
			(pinfunction "IO_L12P_T1_MRCC_16")
			(pintype "bidirectional+no_connect")
		)
		(pad "E12" smd circle
			(at 0.5 -6.5 270)
			(size 0.51 0.51)
			(layers "F.Cu" "F.Mask" "F.Paste")
			(net 323 "unconnected-(U3F-IO_L10N_T1_16-PadE12)")
			(pinfunction "IO_L10N_T1_16")
			(pintype "bidirectional+no_connect")
		)
		(pad "E13" smd circle
			(at 1.5 -6.5 270)
			(size 0.51 0.51)
			(layers "F.Cu" "F.Mask" "F.Paste")
			(net 324 "unconnected-(U3F-IO_L10P_T1_16-PadE13)")
			(pinfunction "IO_L10P_T1_16")
			(pintype "bidirectional+no_connect")
		)
		(pad "E14" smd circle
			(at 2.5 -6.5 270)
			(size 0.51 0.51)
			(layers "F.Cu" "F.Mask" "F.Paste")
			(net 325 "unconnected-(U3G-IO_L6P_T0_15-PadE14)")
			(pinfunction "IO_L6P_T0_15")
			(pintype "bidirectional+no_connect")
		)
		(pad "E15" smd circle
			(at 3.5 -6.5 270)
			(size 0.51 0.51)
			(layers "F.Cu" "F.Mask" "F.Paste")
			(net 459 "3V3_SYS")
			(pinfunction "VCCO_15")
			(pintype "passive")
		)
		(pad "E16" smd circle
			(at 4.5 -6.5 270)
			(size 0.51 0.51)
			(layers "F.Cu" "F.Mask" "F.Paste")
			(net 24 "ETH_RSTN")
			(pinfunction "IO_L14P_T2_SRCC_15")
			(pintype "bidirectional")
		)
		(pad "E17" smd circle
			(at 5.5 -6.5 270)
			(size 0.51 0.51)
			(layers "F.Cu" "F.Mask" "F.Paste")
			(net 30 "ETH_TX_CLK")
			(pinfunction "IO_L13P_T2_MRCC_15")
			(pintype "bidirectional")
		)
		(pad "E18" smd circle
			(at 6.5 -6.5 270)
			(size 0.51 0.51)
			(layers "F.Cu" "F.Mask" "F.Paste")
			(net 326 "unconnected-(U3G-IO_L13N_T2_MRCC_15-PadE18)")
			(pinfunction "IO_L13N_T2_MRCC_15")
			(pintype "bidirectional+no_connect")
		)
		(pad "E19" smd circle
			(at 7.5 -6.5 270)
			(size 0.51 0.51)
			(layers "F.Cu" "F.Mask" "F.Paste")
			(net 327 "unconnected-(U3G-IO_L17N_T2_A25_15-PadE19)")
			(pinfunction "IO_L17N_T2_A25_15")
			(pintype "bidirectional+no_connect")
		)
		(pad "E20" smd circle
			(at 8.5 -6.5 270)
			(size 0.51 0.51)
			(layers "F.Cu" "F.Mask" "F.Paste")
			(net 5 "GND")
			(pinfunction "GND")
			(pintype "passive")
		)
		(pad "E21" smd circle
			(at 9.5 -6.5 270)
			(size 0.51 0.51)
			(layers "F.Cu" "F.Mask" "F.Paste")
			(net 328 "unconnected-(U3H-IO_L7P_T1_D09_14-PadE21)")
			(pinfunction "IO_L7P_T1_D09_14")
			(pintype "bidirectional+no_connect")
		)
		(pad "E22" smd circle
			(at 10.5 -6.5 270)
			(size 0.51 0.51)
			(layers "F.Cu" "F.Mask" "F.Paste")
			(net 329 "unconnected-(U3H-IO_L7N_T1_D10_14-PadE22)")
			(pinfunction "IO_L7N_T1_D10_14")
			(pintype "bidirectional+no_connect")
		)
	)
)
